FILE_TYPE=LIBRARY_PARTS;
primitive 'NB695GDZ';
  pin
    'VIN':
      PIN_NUMBER='(1)';
      PINUSE='POWER';
      NO_LOAD_CHECK='Both';
      NO_IO_CHECK='Both';
      NO_ASSERT_CHECK='TRUE';
      NO_DIR_CHECK='TRUE';
      ALLOW_CONNECT='TRUE';
    'PG':
      PIN_NUMBER='(13)';
      OUTPUT_LOAD='(1.0,-1.0)';
    'PGND':
      PIN_NUMBER='(2)';
      PINUSE='POWER';
      NO_LOAD_CHECK='Both';
      NO_IO_CHECK='Both';
      NO_ASSERT_CHECK='TRUE';
      NO_DIR_CHECK='TRUE';
      ALLOW_CONNECT='TRUE';
    'EN':
      PIN_NUMBER='(5)';
      INPUT_LOAD='(-0.01,0.01)';
    'BST':
      PIN_NUMBER='(9)';
      PINUSE='POWER';
      NO_LOAD_CHECK='Both';
      NO_IO_CHECK='Both';
      NO_ASSERT_CHECK='TRUE';
      NO_DIR_CHECK='TRUE';
      ALLOW_CONNECT='TRUE';
    'AGND':
      PIN_NUMBER='(11)';
      PINUSE='POWER';
      NO_LOAD_CHECK='Both';
      NO_IO_CHECK='Both';
      NO_ASSERT_CHECK='TRUE';
      NO_DIR_CHECK='TRUE';
      ALLOW_CONNECT='TRUE';
    'LP#':
      PIN_NUMBER='(6)';
      INPUT_LOAD='(-0.01,0.01)';
    'C1':
      PIN_NUMBER='(3)';
      INPUT_LOAD='(-0.01,0.01)';
    'C0':
      PIN_NUMBER='(4)';
      INPUT_LOAD='(-0.01,0.01)';
    'MODE':
      PIN_NUMBER='(7)';
      INPUT_LOAD='(-0.01,0.01)';
    'VOUT':
      PIN_NUMBER='(12)';
      PINUSE='POWER';
      NO_LOAD_CHECK='Both';
      NO_IO_CHECK='Both';
      NO_ASSERT_CHECK='TRUE';
      NO_DIR_CHECK='TRUE';
      ALLOW_CONNECT='TRUE';
    'SW':
      PIN_NUMBER='(8)';
      PINUSE='POWER';
      NO_LOAD_CHECK='Both';
      NO_IO_CHECK='Both';
      NO_ASSERT_CHECK='TRUE';
      NO_DIR_CHECK='TRUE';
      ALLOW_CONNECT='TRUE';
    '3V3':
      PIN_NUMBER='(10)';
      PINUSE='POWER';
      NO_LOAD_CHECK='Both';
      NO_IO_CHECK='Both';
      NO_ASSERT_CHECK='TRUE';
      NO_DIR_CHECK='TRUE';
      ALLOW_CONNECT='TRUE';
  end_pin;
  body
    PART_NAME='NB695GDZ';
    BODY_NAME='NB695GDZ';
    PHYS_DES_PREFIX='U';
    CLASS='IC';
  end_body;
end_primitive;

END.
